(kicad_pcb
	(version 20241229)
	(generator "pcbnew")
	(generator_version "9.0")
	(general
		(thickness 1.62)
		(legacy_teardrops no)
	)
	(paper "A3")
	(title_block
		(title "COM Express 7 Baseboard")
		(date "2025-02-04")
		(rev "1.1.2")
		(company "Antmicro Ltd")
		(comment 1 "www.antmicro.com")
		(comment 9 "footprints 757-763 of 802")
	)
	(layers
		(0 "F.Cu" signal)
		(4 "In1.Cu" signal)
		(6 "In2.Cu" signal)
		(8 "In3.Cu" signal)
		(10 "In4.Cu" signal)
		(12 "In5.Cu" signal)
		(14 "In6.Cu" signal)
		(2 "B.Cu" signal)
		(9 "F.Adhes" user "F.Adhesive")
		(11 "B.Adhes" user "B.Adhesive")
		(13 "F.Paste" user)
		(15 "B.Paste" user)
		(5 "F.SilkS" user "F.Silkscreen")
		(7 "B.SilkS" user "B.Silkscreen")
		(1 "F.Mask" user)
		(3 "B.Mask" user)
		(17 "Dwgs.User" user "User.Drawings")
		(19 "Cmts.User" user "User.Comments")
		(21 "Eco1.User" user "User.Eco1")
		(23 "Eco2.User" user "User.Eco2")
		(25 "Edge.Cuts" user)
		(27 "Margin" user)
		(31 "F.CrtYd" user "F.Courtyard")
		(29 "B.CrtYd" user "B.Courtyard")
		(35 "F.Fab" user)
		(33 "B.Fab" user)
	)
	(footprint "antmicro-footprints:TP_SMD_0.75mm"
		(layer "B.Cu")
		(at 191.55 163.4 -90)
		(property "Reference" "TP41"
			(at -1 0.35 90)
			(layer "B.SilkS")
			(effects
				(font
					(size 0.7 0.7)
					(thickness 0.15)
				)
				(justify right top mirror)
			)
		)
		(property "Value" "TP_0.75mm_SMD"
			(at 3.225 -53.865 90)
			(layer "B.Fab")
			(hide yes)
			(effects
				(font
					(size 0.7 0.7)
					(thickness 0.15)
				)
				(justify left bottom mirror)
			)
		)
		(property "Author" "Antmicro"
			(at 432.8 311.62 90)
			(layer "B.Fab")
			(hide yes)
			(effects
				(font
					(size 1 1)
					(thickness 0.15)
				)
				(justify mirror)
			)
		)
		(property "License" "Apache-2.0"
			(at 432.8 311.62 90)
			(layer "B.Fab")
			(hide yes)
			(effects
				(font
					(size 1 1)
					(thickness 0.15)
				)
				(justify mirror)
			)
		)
		(property "MPN" ""
			(at 432.8 311.62 90)
			(layer "B.Fab")
			(hide yes)
			(effects
				(font
					(size 1 1)
					(thickness 0.15)
				)
				(justify mirror)
			)
		)
		(property "Manufacturer" ""
			(at 432.8 311.62 90)
			(layer "B.Fab")
			(hide yes)
			(effects
				(font
					(size 1 1)
					(thickness 0.15)
				)
				(justify mirror)
			)
		)
		(property "Public" "False"
			(at 432.8 311.62 90)
			(layer "B.Fab")
			(hide yes)
			(effects
				(font
					(size 1 1)
					(thickness 0.15)
				)
				(justify mirror)
			)
		)
		(sheetname "Com Express 7 MGMT")
		(sheetfile "com_express_7_mgmt.kicad_sch")
		(attr exclude_from_pos_files exclude_from_bom)
		(fp_circle
			(center 0 0)
			(end 0.475 0)
			(stroke
				(width 0.05)
				(type default)
			)
			(fill no)
			(layer "B.CrtYd")
		)
		(pad "1" smd circle
			(at 0 0 270)
			(size 0.75 0.75)
			(layers "B.Cu" "B.Mask")
			(net 370 "Net-(J12D-SPKR)")
			(pinfunction "1")
			(pintype "passive")
			(teardrops
				(best_length_ratio 0.4)
				(max_length 1)
				(best_width_ratio 0.9)
				(max_width 2)
				(curved_edges yes)
				(filter_ratio 0.9)
				(enabled yes)
				(allow_two_segments yes)
				(prefer_zone_connections yes)
			)
		)
	)
	(footprint "antmicro-footprints:C_0402_1005Metric"
		(layer "B.Cu")
		(at 132.45 157.14 -90)
		(descr "Capacitor SMD 0402")
		(tags "capacitor SMD 0402")
		(property "Reference" "C212"
			(at -1.33 0.55 90)
			(layer "B.SilkS")
			(effects
				(font
					(size 0.7 0.7)
					(thickness 0.15)
				)
				(justify left bottom mirror)
			)
		)
		(property "Value" "C_100n_0402"
			(at -1.022927 -2.155213 90)
			(layer "B.Fab")
			(effects
				(font
					(size 0.7 0.7)
					(thickness 0.15)
				)
				(justify left bottom mirror)
			)
		)
		(property "Datasheet" "https://www.murata.com/products/productdetail?partno=GRM155R61H104KE14%23"
			(at 0 0 270)
			(layer "F.Fab")
			(hide yes)
			(effects
				(font
					(size 1.27 1.27)
					(thickness 0.15)
				)
			)
		)
		(property "Author" "Antmicro"
			(at -24.69 289.59 0)
			(layer "B.Fab")
			(hide yes)
			(effects
				(font
					(size 1 1)
					(thickness 0.15)
				)
				(justify mirror)
			)
		)
		(property "Dielectric" "X5R"
			(at -24.69 289.59 0)
			(layer "B.Fab")
			(hide yes)
			(effects
				(font
					(size 1 1)
					(thickness 0.15)
				)
				(justify mirror)
			)
		)
		(property "License" "Apache-2.0"
			(at -24.69 289.59 0)
			(layer "B.Fab")
			(hide yes)
			(effects
				(font
					(size 1 1)
					(thickness 0.15)
				)
				(justify mirror)
			)
		)
		(property "MPN" "GRM155R61H104KE14D"
			(at -24.69 289.59 0)
			(layer "B.Fab")
			(hide yes)
			(effects
				(font
					(size 1 1)
					(thickness 0.15)
				)
				(justify mirror)
			)
		)
		(property "Manufacturer" "Murata"
			(at -24.69 289.59 0)
			(layer "B.Fab")
			(hide yes)
			(effects
				(font
					(size 1 1)
					(thickness 0.15)
				)
				(justify mirror)
			)
		)
		(property "Public" "False"
			(at -24.69 289.59 0)
			(layer "B.Fab")
			(hide yes)
			(effects
				(font
					(size 1 1)
					(thickness 0.15)
				)
				(justify mirror)
			)
		)
		(property "Val" "100n"
			(at -24.69 289.59 0)
			(layer "B.Fab")
			(hide yes)
			(effects
				(font
					(size 1 1)
					(thickness 0.15)
				)
				(justify mirror)
			)
		)
		(property "Voltage" "50V"
			(at -24.69 289.59 0)
			(layer "B.Fab")
			(hide yes)
			(effects
				(font
					(size 1 1)
					(thickness 0.15)
				)
				(justify mirror)
			)
		)
		(sheetname "2xSFP+")
		(sheetfile "2xSFP+.kicad_sch")
		(attr smd)
		(fp_rect
			(start -0.925 0.47)
			(end 0.925 -0.47)
			(stroke
				(width 0.05)
				(type default)
			)
			(fill no)
			(layer "B.CrtYd")
		)
		(fp_line
			(start -0.494 0.25)
			(end -0.494 -0.248)
			(stroke
				(width 0.15)
				(type solid)
			)
			(layer "B.Fab")
		)
		(fp_line
			(start 0.504 0.25)
			(end -0.494 0.25)
			(stroke
				(width 0.15)
				(type solid)
			)
			(layer "B.Fab")
		)
		(fp_line
			(start -0.494 -0.248)
			(end 0.504 -0.248)
			(stroke
				(width 0.15)
				(type solid)
			)
			(layer "B.Fab")
		)
		(fp_line
			(start 0.504 -0.248)
			(end 0.504 0.25)
			(stroke
				(width 0.15)
				(type solid)
			)
			(layer "B.Fab")
		)
		(pad "1" smd roundrect
			(at -0.48 0 270)
			(size 0.59 0.64)
			(layers "B.Cu" "B.Mask" "B.Paste")
			(roundrect_rratio 0.25)
			(net 53 "/2xSFP+/SH")
			(pintype "passive")
			(teardrops
				(best_length_ratio 0.2)
				(max_length 1)
				(best_width_ratio 0.9)
				(max_width 2)
				(curved_edges yes)
				(filter_ratio 0.9)
				(enabled yes)
				(allow_two_segments yes)
				(prefer_zone_connections yes)
			)
		)
		(pad "2" smd roundrect
			(at 0.48 0 270)
			(size 0.59 0.64)
			(layers "B.Cu" "B.Mask" "B.Paste")
			(roundrect_rratio 0.25)
			(net 1 "GND")
			(pintype "passive")
			(teardrops
				(best_length_ratio 0.2)
				(max_length 1)
				(best_width_ratio 0.9)
				(max_width 2)
				(curved_edges yes)
				(filter_ratio 0.9)
				(enabled yes)
				(allow_two_segments yes)
				(prefer_zone_connections yes)
			)
		)
	)
	(footprint "antmicro-footprints:R_0402_1005Metric"
		(layer "B.Cu")
		(at 126.09 136.06 180)
		(descr "Resistor SMD 0402")
		(tags "resistor SMD 0402")
		(property "Reference" "R293"
			(at 0.79 -0.45 0)
			(layer "B.SilkS")
			(effects
				(font
					(size 0.7 0.7)
					(thickness 0.15)
				)
				(justify left bottom mirror)
			)
		)
		(property "Value" "R_10k_0402"
			(at -1.011843 -1.772047 0)
			(layer "B.Fab")
			(effects
				(font
					(size 0.7 0.7)
					(thickness 0.15)
				)
				(justify left bottom mirror)
			)
		)
		(property "Datasheet" "https://www.bourns.com/docs/product-datasheets/cr.pdf"
			(at 0 0 180)
			(layer "F.Fab")
			(hide yes)
			(effects
				(font
					(size 1.27 1.27)
					(thickness 0.15)
				)
			)
		)
		(property "Author" "Antmicro"
			(at 252.18 272.12 0)
			(layer "B.Fab")
			(hide yes)
			(effects
				(font
					(size 1 1)
					(thickness 0.15)
				)
				(justify mirror)
			)
		)
		(property "License" "Apache-2.0"
			(at 252.18 272.12 0)
			(layer "B.Fab")
			(hide yes)
			(effects
				(font
					(size 1 1)
					(thickness 0.15)
				)
				(justify mirror)
			)
		)
		(property "MPN" "CR0402-FX-1002GLF"
			(at 252.18 272.12 0)
			(layer "B.Fab")
			(hide yes)
			(effects
				(font
					(size 1 1)
					(thickness 0.15)
				)
				(justify mirror)
			)
		)
		(property "Manufacturer" "Bourns"
			(at 252.18 272.12 0)
			(layer "B.Fab")
			(hide yes)
			(effects
				(font
					(size 1 1)
					(thickness 0.15)
				)
				(justify mirror)
			)
		)
		(property "Public" "False"
			(at 252.18 272.12 0)
			(layer "B.Fab")
			(hide yes)
			(effects
				(font
					(size 1 1)
					(thickness 0.15)
				)
				(justify mirror)
			)
		)
		(property "Tolerance" "1%"
			(at 252.18 272.12 0)
			(layer "B.Fab")
			(hide yes)
			(effects
				(font
					(size 1 1)
					(thickness 0.15)
				)
				(justify mirror)
			)
		)
		(property "Val" "10k"
			(at 252.18 272.12 0)
			(layer "B.Fab")
			(hide yes)
			(effects
				(font
					(size 1 1)
					(thickness 0.15)
				)
				(justify mirror)
			)
		)
		(sheetname "KR to SFI #2")
		(sheetfile "kr_sfi.kicad_sch")
		(attr smd)
		(fp_rect
			(start -0.925 0.47)
			(end 0.925 -0.47)
			(stroke
				(width 0.05)
				(type default)
			)
			(fill no)
			(layer "B.CrtYd")
		)
		(fp_rect
			(start -0.5 0.25)
			(end 0.5 -0.25)
			(stroke
				(width 0.15)
				(type solid)
			)
			(fill no)
			(layer "B.Fab")
		)
		(pad "1" smd roundrect
			(at -0.48 0 180)
			(size 0.59 0.64)
			(layers "B.Cu" "B.Mask" "B.Paste")
			(roundrect_rratio 0.25)
			(net 143 "/2xSFP+/KR to SFI #2/~{RESET}")
			(pintype "passive")
			(teardrops
				(best_length_ratio 0.2)
				(max_length 1)
				(best_width_ratio 0.9)
				(max_width 2)
				(curved_edges yes)
				(filter_ratio 0.9)
				(enabled yes)
				(allow_two_segments yes)
				(prefer_zone_connections yes)
			)
		)
		(pad "2" smd roundrect
			(at 0.48 0 180)
			(size 0.59 0.64)
			(layers "B.Cu" "B.Mask" "B.Paste")
			(roundrect_rratio 0.25)
			(net 78 "+1V8")
			(pintype "passive")
			(teardrops
				(best_length_ratio 0.2)
				(max_length 1)
				(best_width_ratio 0.9)
				(max_width 2)
				(curved_edges yes)
				(filter_ratio 0.9)
				(enabled yes)
				(allow_two_segments yes)
				(prefer_zone_connections yes)
			)
		)
	)
	(footprint "antmicro-footprints:TP_SMD_0.75mm"
		(layer "B.Cu")
		(at 182.35 165.75)
		(property "Reference" "TP26"
			(at -0.35 -0.75 90)
			(layer "B.SilkS")
			(effects
				(font
					(size 0.7 0.7)
					(thickness 0.15)
				)
				(justify right top mirror)
			)
		)
		(property "Value" "TP_0.75mm_SMD"
			(at 3.225 -53.865 0)
			(layer "B.Fab")
			(hide yes)
			(effects
				(font
					(size 0.7 0.7)
					(thickness 0.15)
				)
				(justify right top mirror)
			)
		)
		(property "Author" "Antmicro"
			(at 451.2 306.12 0)
			(layer "B.Fab")
			(hide yes)
			(effects
				(font
					(size 1 1)
					(thickness 0.15)
				)
				(justify mirror)
			)
		)
		(property "License" "Apache-2.0"
			(at 451.2 306.12 0)
			(layer "B.Fab")
			(hide yes)
			(effects
				(font
					(size 1 1)
					(thickness 0.15)
				)
				(justify mirror)
			)
		)
		(property "MPN" ""
			(at 451.2 306.12 0)
			(layer "B.Fab")
			(hide yes)
			(effects
				(font
					(size 1 1)
					(thickness 0.15)
				)
				(justify mirror)
			)
		)
		(property "Manufacturer" ""
			(at 451.2 306.12 0)
			(layer "B.Fab")
			(hide yes)
			(effects
				(font
					(size 1 1)
					(thickness 0.15)
				)
				(justify mirror)
			)
		)
		(property "Public" "False"
			(at 451.2 306.12 0)
			(layer "B.Fab")
			(hide yes)
			(effects
				(font
					(size 1 1)
					(thickness 0.15)
				)
				(justify mirror)
			)
		)
		(sheetname "Com Express 7 MGMT")
		(sheetfile "com_express_7_mgmt.kicad_sch")
		(attr exclude_from_pos_files exclude_from_bom)
		(fp_circle
			(center 0 0)
			(end 0.475 0)
			(stroke
				(width 0.05)
				(type default)
			)
			(fill no)
			(layer "B.CrtYd")
		)
		(pad "1" smd circle
			(at 0 0)
			(size 0.75 0.75)
			(layers "B.Cu" "B.Mask")
			(net 355 "Net-(J12D-LPC_CLK{slash}ESPI_CK)")
			(pinfunction "1")
			(pintype "passive")
			(teardrops
				(best_length_ratio 0.4)
				(max_length 1)
				(best_width_ratio 0.9)
				(max_width 2)
				(curved_edges yes)
				(filter_ratio 0.9)
				(enabled yes)
				(allow_two_segments yes)
				(prefer_zone_connections yes)
			)
		)
	)
	(footprint "antmicro-footprints:TP_SMD_0.75mm"
		(layer "B.Cu")
		(at 123.4 146.76 180)
		(property "Reference" "TP50"
			(at -3.15 -0.45 0)
			(layer "B.SilkS")
			(effects
				(font
					(size 0.7 0.7)
					(thickness 0.15)
				)
				(justify left bottom mirror)
			)
		)
		(property "Value" "TP_0.75mm_SMD"
			(at 0 -1.2 0)
			(layer "B.Fab")
			(effects
				(font
					(size 0.7 0.7)
					(thickness 0.15)
				)
				(justify left bottom mirror)
			)
		)
		(property "Author" "Antmicro"
			(at 246.8 293.52 0)
			(layer "B.Fab")
			(hide yes)
			(effects
				(font
					(size 1 1)
					(thickness 0.15)
				)
				(justify mirror)
			)
		)
		(property "License" "Apache-2.0"
			(at 246.8 293.52 0)
			(layer "B.Fab")
			(hide yes)
			(effects
				(font
					(size 1 1)
					(thickness 0.15)
				)
				(justify mirror)
			)
		)
		(property "MPN" ""
			(at 246.8 293.52 0)
			(layer "B.Fab")
			(hide yes)
			(effects
				(font
					(size 1 1)
					(thickness 0.15)
				)
				(justify mirror)
			)
		)
		(property "Manufacturer" ""
			(at 246.8 293.52 0)
			(layer "B.Fab")
			(hide yes)
			(effects
				(font
					(size 1 1)
					(thickness 0.15)
				)
				(justify mirror)
			)
		)
		(property "Public" "False"
			(at 246.8 293.52 0)
			(layer "B.Fab")
			(hide yes)
			(effects
				(font
					(size 1 1)
					(thickness 0.15)
				)
				(justify mirror)
			)
		)
		(sheetname "PCIe redriver")
		(sheetfile "pcie_redriver.kicad_sch")
		(attr exclude_from_pos_files exclude_from_bom)
		(fp_circle
			(center 0 0)
			(end 0.475 0)
			(stroke
				(width 0.05)
				(type default)
			)
			(fill no)
			(layer "B.CrtYd")
		)
		(pad "1" smd circle
			(at 0 0 180)
			(size 0.75 0.75)
			(layers "B.Cu" "B.Mask")
			(net 713 "Net-(U39-SCL)")
			(pinfunction "1")
			(pintype "passive")
			(teardrops
				(best_length_ratio 0.4)
				(max_length 1)
				(best_width_ratio 0.9)
				(max_width 2)
				(curved_edges yes)
				(filter_ratio 0.9)
				(enabled yes)
				(allow_two_segments yes)
				(prefer_zone_connections yes)
			)
		)
	)
	(footprint "antmicro-footprints:TP_SMD_0.75mm"
		(layer "B.Cu")
		(at 176.25 163.8)
		(property "Reference" "TP24"
			(at -0.25 -2.3 270)
			(layer "B.SilkS")
			(effects
				(font
					(size 0.7 0.7)
					(thickness 0.15)
				)
				(justify right top mirror)
			)
		)
		(property "Value" "TP_0.75mm_SMD"
			(at 3.225 -53.865 0)
			(layer "B.Fab")
			(hide yes)
			(effects
				(font
					(size 0.7 0.7)
					(thickness 0.15)
				)
				(justify right top mirror)
			)
		)
		(property "Author" "Antmicro"
			(at 457.2 308.02 0)
			(layer "B.Fab")
			(hide yes)
			(effects
				(font
					(size 1 1)
					(thickness 0.15)
				)
				(justify mirror)
			)
		)
		(property "License" "Apache-2.0"
			(at 457.2 308.02 0)
			(layer "B.Fab")
			(hide yes)
			(effects
				(font
					(size 1 1)
					(thickness 0.15)
				)
				(justify mirror)
			)
		)
		(property "MPN" ""
			(at 457.2 308.02 0)
			(layer "B.Fab")
			(hide yes)
			(effects
				(font
					(size 1 1)
					(thickness 0.15)
				)
				(justify mirror)
			)
		)
		(property "Manufacturer" ""
			(at 457.2 308.02 0)
			(layer "B.Fab")
			(hide yes)
			(effects
				(font
					(size 1 1)
					(thickness 0.15)
				)
				(justify mirror)
			)
		)
		(property "Public" "False"
			(at 457.2 308.02 0)
			(layer "B.Fab")
			(hide yes)
			(effects
				(font
					(size 1 1)
					(thickness 0.15)
				)
				(justify mirror)
			)
		)
		(sheetname "Com Express 7 MGMT")
		(sheetfile "com_express_7_mgmt.kicad_sch")
		(attr exclude_from_pos_files exclude_from_bom)
		(fp_circle
			(center 0 0)
			(end 0.475 0)
			(stroke
				(width 0.05)
				(type default)
			)
			(fill no)
			(layer "B.CrtYd")
		)
		(pad "1" smd circle
			(at 0 0)
			(size 0.75 0.75)
			(layers "B.Cu" "B.Mask")
			(net 350 "Net-(J12D-LPC_AD1{slash}ESPI_IO_1)")
			(pinfunction "1")
			(pintype "passive")
			(teardrops
				(best_length_ratio 0.4)
				(max_length 1)
				(best_width_ratio 0.9)
				(max_width 2)
				(curved_edges yes)
				(filter_ratio 0.9)
				(enabled yes)
				(allow_two_segments yes)
				(prefer_zone_connections yes)
			)
		)
	)
	(footprint "antmicro-footprints:C_0402_1005Metric"
		(layer "B.Cu")
		(at 196.715146 141.541851 135)
		(descr "Capacitor SMD 0402")
		(tags "capacitor SMD 0402")
		(property "Reference" "C123"
			(at -3.530586 -0.359976 135)
			(layer "B.SilkS")
			(effects
				(font
					(size 0.7 0.7)
					(thickness 0.15)
				)
				(justify right bottom mirror)
			)
		)
		(property "Value" "C_220n_0402"
			(at -1.022927 -2.155213 135)
			(layer "B.Fab")
			(effects
				(font
					(size 0.7 0.7)
					(thickness 0.15)
				)
				(justify right bottom mirror)
			)
		)
		(property "Datasheet" "https://www.yageo.com/en/Chart/Download/pdf/CC0402KRX5R6BB224"
			(at 0 0 135)
			(layer "F.Fab")
			(hide yes)
			(effects
				(font
					(size 1.27 1.27)
					(thickness 0.15)
				)
			)
		)
		(property "Author" "Antmicro"
			(at 339.3 -42.5 45)
			(layer "B.Fab")
			(hide yes)
			(effects
				(font
					(size 1 1)
					(thickness 0.15)
				)
				(justify mirror)
			)
		)
		(property "Dielectric" ""
			(at 339.3 -42.5 45)
			(layer "B.Fab")
			(hide yes)
			(effects
				(font
					(size 1 1)
					(thickness 0.15)
				)
				(justify mirror)
			)
		)
		(property "License" "Apache-2.0"
			(at 339.3 -42.5 45)
			(layer "B.Fab")
			(hide yes)
			(effects
				(font
					(size 1 1)
					(thickness 0.15)
				)
				(justify mirror)
			)
		)
		(property "MPN" "CC0402KRX5R6BB224"
			(at 339.3 -42.5 45)
			(layer "B.Fab")
			(hide yes)
			(effects
				(font
					(size 1 1)
					(thickness 0.15)
				)
				(justify mirror)
			)
		)
		(property "Manufacturer" "YAGEO"
			(at 339.3 -42.5 45)
			(layer "B.Fab")
			(hide yes)
			(effects
				(font
					(size 1 1)
					(thickness 0.15)
				)
				(justify mirror)
			)
		)
		(property "Public" "False"
			(at 339.3 -42.5 45)
			(layer "B.Fab")
			(hide yes)
			(effects
				(font
					(size 1 1)
					(thickness 0.15)
				)
				(justify mirror)
			)
		)
		(property "Val" "220n"
			(at 339.3 -42.5 45)
			(layer "B.Fab")
			(hide yes)
			(effects
				(font
					(size 1 1)
					(thickness 0.15)
				)
				(justify mirror)
			)
		)
		(property "Voltage" ""
			(at 339.3 -42.5 45)
			(layer "B.Fab")
			(hide yes)
			(effects
				(font
					(size 1 1)
					(thickness 0.15)
				)
				(justify mirror)
			)
		)
		(sheetname "PCIe redriver")
		(sheetfile "pcie_redriver.kicad_sch")
		(attr smd)
		(fp_poly
			(pts
				(xy -0.925 0.47) (xy 0.925 0.47) (xy 0.925 -0.47) (xy -0.925 -0.47)
			)
			(stroke
				(width 0.05)
				(type default)
			)
			(fill no)
			(layer "B.CrtYd")
		)
		(fp_line
			(start 0.504 -0.248)
			(end 0.504 0.25)
			(stroke
				(width 0.15)
				(type solid)
			)
			(layer "B.Fab")
		)
		(fp_line
			(start 0.504 0.25)
			(end -0.494 0.25)
			(stroke
				(width 0.15)
				(type solid)
			)
			(layer "B.Fab")
		)
		(fp_line
			(start -0.494 -0.248)
			(end 0.504 -0.248)
			(stroke
				(width 0.15)
				(type solid)
			)
			(layer "B.Fab")
		)
		(fp_line
			(start -0.494 0.25)
			(end -0.494 -0.248)
			(stroke
				(width 0.15)
				(type solid)
			)
			(layer "B.Fab")
		)
		(pad "1" smd roundrect
			(at -0.48 0 135)
			(size 0.59 0.64)
			(layers "B.Cu" "B.Mask" "B.Paste")
			(roundrect_rratio 0.25)
			(net 209 "/Com Express 7 Interfaces/PCIe_{B1x4}.RX3-")
			(pintype "passive")
			(teardrops
				(best_length_ratio 0.2)
				(max_length 1)
				(best_width_ratio 0.9)
				(max_width 2)
				(curved_edges yes)
				(filter_ratio 0.9)
				(enabled yes)
				(allow_two_segments yes)
				(prefer_zone_connections yes)
			)
		)
		(pad "2" smd roundrect
			(at 0.48 0 135)
			(size 0.59 0.64)
			(layers "B.Cu" "B.Mask" "B.Paste")
			(roundrect_rratio 0.25)
			(net 956 "/PCIe redriver/PCIe_{I}_C.RX3-")
			(pintype "passive")
			(teardrops
				(best_length_ratio 0.2)
				(max_length 1)
				(best_width_ratio 0.9)
				(max_width 2)
				(curved_edges yes)
				(filter_ratio 0.9)
				(enabled yes)
				(allow_two_segments yes)
				(prefer_zone_connections yes)
			)
		)
	)
)
